(kicad_pcb
	(version 20241229)
	(generator "pcbnew")
	(generator_version "9.0")
	(general
		(thickness 1.61)
		(legacy_teardrops no)
	)
	(paper "A3")
	(title_block
		(title "RDIMM DDR5 Tester")
		(date "2026-05-21")
		(rev "2.2.0")
		(company "Antmicro")
		(comment 9 "footprints 107-108 of 796")
	)
	(layers
		(0 "F.Cu" signal)
		(4 "In1.Cu" power)
		(6 "In2.Cu" mixed)
		(8 "In3.Cu" power)
		(10 "In4.Cu" mixed)
		(12 "In5.Cu" power)
		(14 "In6.Cu" mixed)
		(16 "In7.Cu" power)
		(18 "In8.Cu" power)
		(20 "In9.Cu" mixed)
		(22 "In10.Cu" power)
		(2 "B.Cu" signal)
		(9 "F.Adhes" user "F.Adhesive")
		(11 "B.Adhes" user "B.Adhesive")
		(13 "F.Paste" user)
		(15 "B.Paste" user)
		(5 "F.SilkS" user "F.Silkscreen")
		(7 "B.SilkS" user "B.Silkscreen")
		(1 "F.Mask" user)
		(3 "B.Mask" user)
		(17 "Dwgs.User" user "User.Drawings")
		(19 "Cmts.User" user "User.Comments")
		(21 "Eco1.User" user "User.Eco1")
		(23 "Eco2.User" user "User.Eco2")
		(25 "Edge.Cuts" user)
		(27 "Margin" user)
		(31 "F.CrtYd" user "F.Courtyard")
		(29 "B.CrtYd" user "B.Courtyard")
		(35 "F.Fab" user)
		(33 "B.Fab" user)
	)
	(footprint "antmicro-footprints:NetTie-2_SMD_Pad0.127mm"
		(layer "F.Cu")
		(at 256.573 162.423998 180)
		(descr "Net tie, 2 pin, 0.127mm  SMD pads")
		(tags "net tie")
		(property "Reference" "NT16"
			(at -0.128 -1.345 0)
			(layer "F.SilkS")
			(hide yes)
			(effects
				(font
					(size 0.7 0.7)
					(thickness 0.15)
				)
				(justify right bottom)
			)
		)
		(property "Value" "Net-Tie_P0.127mm"
			(at 0 1.199 0)
			(layer "F.Fab")
			(effects
				(font
					(size 0.7 0.7)
					(thickness 0.15)
				)
				(justify right bottom)
			)
		)
		(property "MPN" ""
			(at 0 0 180)
			(unlocked yes)
			(layer "F.Fab")
			(hide yes)
			(effects
				(font
					(size 1 1)
					(thickness 0.15)
				)
			)
		)
		(property "Manufacturer" ""
			(at 0 0 180)
			(unlocked yes)
			(layer "F.Fab")
			(hide yes)
			(effects
				(font
					(size 1 1)
					(thickness 0.15)
				)
			)
		)
		(property "Author" "Antmicro"
			(at 0 0 180)
			(unlocked yes)
			(layer "F.Fab")
			(hide yes)
			(effects
				(font
					(size 1 1)
					(thickness 0.15)
				)
			)
		)
		(property "License" "Apache-2.0"
			(at 0 0 180)
			(unlocked yes)
			(layer "F.Fab")
			(hide yes)
			(effects
				(font
					(size 1 1)
					(thickness 0.15)
				)
			)
		)
		(property ki_fp_filters "Net*Tie*")
		(sheetname "/Supply/DC-DC IO/")
		(sheetfile "dc-dc-io.kicad_sch")
		(attr through_hole exclude_from_pos_files exclude_from_bom)
		(net_tie_pad_groups "1, 2")
		(fp_poly
			(pts
				(xy -0.0635 -0.0635) (xy 0.0625 -0.0635) (xy 0.0625 0.0635) (xy -0.0635 0.0635)
			)
			(stroke
				(width 0)
				(type solid)
			)
			(fill yes)
			(layer "F.Cu")
		)
		(fp_poly
			(pts
				(xy 0.2 -0.16) (xy 0.29 -0.07) (xy 0.29 0.07) (xy 0.2 0.16) (xy -0.2 0.16) (xy -0.29 0.07) (xy -0.29 -0.06)
				(xy -0.19 -0.16)
			)
			(stroke
				(width 0.05)
				(type solid)
			)
			(fill no)
			(layer "F.CrtYd")
		)
		(fp_text user "${REFERENCE}"
			(at -0.128 3.2 180)
			(layer "F.Fab")
			(effects
				(font
					(size 0.7 0.7)
					(thickness 0.15)
				)
				(justify left bottom)
			)
		)
		(fp_text user "Author: Antmicro"
			(at -0.128 4.4 180)
			(layer "F.Fab")
			(effects
				(font
					(size 0.7 0.7)
					(thickness 0.15)
				)
				(justify left bottom)
			)
		)
		(fp_text user "License: Apache-2.0"
			(at -0.128 5.6 180)
			(layer "F.Fab")
			(effects
				(font
					(size 0.7 0.7)
					(thickness 0.15)
				)
				(justify left bottom)
			)
		)
		(pad "1" smd roundrect
			(at -0.127 0)
			(size 0.127 0.127)
			(layers "F.Cu")
			(roundrect_rratio 0.5)
			(chamfer_ratio 0)
			(chamfer top_left bottom_left)
			(net 696 "/Supply/DC-DC IO/1V2_SEN_-")
			(pinfunction "1")
			(pintype "passive")
		)
		(pad "2" smd roundrect
			(at 0.126 0 180)
			(size 0.127 0.127)
			(layers "F.Cu")
			(roundrect_rratio 0.5)
			(chamfer_ratio 0)
			(chamfer top_left bottom_left)
			(net 150 "+1V2")
			(pinfunction "2")
			(pintype "passive")
		)
	)
	(footprint "antmicro-footprints:NetTie-2_SMD_Pad0.127mm"
		(layer "F.Cu")
		(at 245.763 177.55 180)
		(descr "Net tie, 2 pin, 0.127mm  SMD pads")
		(tags "net tie")
		(property "Reference" "NT9"
			(at -0.128 -1.345 0)
			(layer "F.SilkS")
			(hide yes)
			(effects
				(font
					(size 0.7 0.7)
					(thickness 0.15)
				)
				(justify right bottom)
			)
		)
		(property "Value" "Net-Tie_P0.127mm"
			(at 0 1.199 0)
			(layer "F.Fab")
			(effects
				(font
					(size 0.7 0.7)
					(thickness 0.15)
				)
				(justify right bottom)
			)
		)
		(property "MPN" ""
			(at 0 0 180)
			(unlocked yes)
			(layer "F.Fab")
			(hide yes)
			(effects
				(font
					(size 1 1)
					(thickness 0.15)
				)
			)
		)
		(property "Manufacturer" ""
			(at 0 0 180)
			(unlocked yes)
			(layer "F.Fab")
			(hide yes)
			(effects
				(font
					(size 1 1)
					(thickness 0.15)
				)
			)
		)
		(property "Author" "Antmicro"
			(at 0 0 180)
			(unlocked yes)
			(layer "F.Fab")
			(hide yes)
			(effects
				(font
					(size 1 1)
					(thickness 0.15)
				)
			)
		)
		(property "License" "Apache-2.0"
			(at 0 0 180)
			(unlocked yes)
			(layer "F.Fab")
			(hide yes)
			(effects
				(font
					(size 1 1)
					(thickness 0.15)
				)
			)
		)
		(property ki_fp_filters "Net*Tie*")
		(sheetname "/Supply/DC-DC AUX, MGT/")
		(sheetfile "dc-dc-aux-mgt.kicad_sch")
		(attr through_hole exclude_from_pos_files exclude_from_bom)
		(net_tie_pad_groups "1, 2")
		(fp_poly
			(pts
				(xy -0.0635 -0.0635) (xy 0.0625 -0.0635) (xy 0.0625 0.0635) (xy -0.0635 0.0635)
			)
			(stroke
				(width 0)
				(type solid)
			)
			(fill yes)
			(layer "F.Cu")
		)
		(fp_poly
			(pts
				(xy 0.2 -0.16) (xy 0.29 -0.07) (xy 0.29 0.07) (xy 0.2 0.16) (xy -0.2 0.16) (xy -0.29 0.07) (xy -0.29 -0.06)
				(xy -0.19 -0.16)
			)
			(stroke
				(width 0.05)
				(type solid)
			)
			(fill no)
			(layer "F.CrtYd")
		)
		(fp_text user "License: Apache-2.0"
			(at -0.128 5.6 180)
			(layer "F.Fab")
			(effects
				(font
					(size 0.7 0.7)
					(thickness 0.15)
				)
				(justify left bottom)
			)
		)
		(fp_text user "Author: Antmicro"
			(at -0.128 4.4 180)
			(layer "F.Fab")
			(effects
				(font
					(size 0.7 0.7)
					(thickness 0.15)
				)
				(justify left bottom)
			)
		)
		(fp_text user "${REFERENCE}"
			(at -0.128 3.2 180)
			(layer "F.Fab")
			(effects
				(font
					(size 0.7 0.7)
					(thickness 0.15)
				)
				(justify left bottom)
			)
		)
		(pad "1" smd roundrect
			(at -0.127 0)
			(size 0.127 0.127)
			(layers "F.Cu")
			(roundrect_rratio 0.5)
			(chamfer_ratio 0)
			(chamfer top_left bottom_left)
			(net 689 "/Supply/DC-DC AUX, MGT/1V8_SEN_-")
			(pinfunction "1")
			(pintype "passive")
		)
		(pad "2" smd roundrect
			(at 0.126 0 180)
			(size 0.127 0.127)
			(layers "F.Cu")
			(roundrect_rratio 0.5)
			(chamfer_ratio 0)
			(chamfer top_left bottom_left)
			(net 797 "+1V8")
			(pinfunction "2")
			(pintype "passive")
		)
	)
)
